(kicad_pcb
	(version 20260206)
	(generator "pcbnew")
	(generator_version "10.0")
	(general
		(thickness 1.6)
		(legacy_teardrops no)
	)
	(paper "A4")
	(title_block
		(title "panther-plus-userver — 13130-1b_20150205.brd")
		(comment 1 "Honey Badger (Wiwynn) / footprint 624 of 1509 (DIMM4), pads 51-57 of 210")
	)
	(layers
		(0 "F.Cu" signal "TOP")
		(4 "In1.Cu" signal "L2")
		(6 "In2.Cu" signal "L3")
		(8 "In3.Cu" signal "L4")
		(10 "In4.Cu" signal "L5")
		(12 "In5.Cu" signal "L6")
		(14 "In6.Cu" signal "L7")
		(16 "In7.Cu" signal "L8")
		(18 "In8.Cu" signal "L9")
		(20 "In9.Cu" signal "L10")
		(22 "In10.Cu" signal "L11")
		(2 "B.Cu" signal "BOTTOM")
		(9 "F.Adhes" user "F.Adhesive")
		(11 "B.Adhes" user "B.Adhesive")
		(13 "F.Paste" user "Package Geometry/Pastemask Top")
		(15 "B.Paste" user "Package Geometry/Pastemask Bottom")
		(5 "F.SilkS" user "Ref Des/Silkscreen Top")
		(7 "B.SilkS" user "Ref Des/Silkscreen Bottom")
		(1 "F.Mask" user "Board Geometry/Soldermask Top")
		(3 "B.Mask" user "Board Geometry/Soldermask Bottom")
		(17 "Dwgs.User" user "User.Drawings")
		(19 "Cmts.User" user "User.Comments")
		(21 "Eco1.User" user "User.Eco1")
		(23 "Eco2.User" user "User.Eco2")
		(25 "Edge.Cuts" user "Board Geometry/Outline")
		(27 "Margin" user)
		(31 "F.CrtYd" user "Package Geometry/Place Bound Top")
		(29 "B.CrtYd" user "Package Geometry/Place Bound Bottom")
		(35 "F.Fab" user "Ref Des/Assembly Top")
		(33 "B.Fab" user "Ref Des/Assembly Bottom")
	)
	(footprint ""
		(layer "F.Cu")
		(at 159.999934 -5.790692)
		(property "Reference" "DIMM4"
			(at 0 0 0)
			(layer "F.SilkS")
			(hide yes)
			(effects
				(font
					(size 1.27 1.27)
				)
			)
		)
		(property "Value" "DDR3-204P-174-COLAY-1-GP"
			(at -40.682164 -17.468088 0)
			(unlocked yes)
			(layer "F.Fab")
			(hide yes)
			(effects
				(font
					(size 1.016 1.016)
					(thickness 0.1524)
				)
			)
		)
		(property "Device Type" "AS0A626-H8SN-7H-COLAY-1"
			(at -40.682164 -18.992088 0)
			(unlocked yes)
			(layer "F.Fab")
			(hide yes)
			(effects
				(font
					(size 1.016 1.016)
					(thickness 0.1524)
				)
			)
		)
		(duplicate_pad_numbers_are_jumpers no)
		(pad "49" smd custom
			(at -17.249902 4.106672)
			(size 0.1143 0.1143)
			(layers "F.Cu" "F.Mask" "F.Paste")
			(net "M_B_DQ22")
			(options
				(clearance outline)
				(anchor circle)
			)
			(primitives
				(gr_poly
					(pts
						(xy 0 0.9017) (xy -0.03175 0.89916) (xy -0.0635 0.889) (xy -0.09144 0.87376) (xy -0.11684 0.85344)
						(xy -0.13716 0.82804) (xy -0.1524 0.8001) (xy -0.16256 0.76835) (xy -0.1651 0.7366) (xy -0.1651 -0.13462)
						(xy -0.17272 -0.14224) (xy -0.19812 -0.1778) (xy -0.2032 -0.18796) (xy -0.20701 -0.19685) (xy -0.21209 -0.20701)
						(xy -0.2159 -0.21717) (xy -0.21844 -0.22733) (xy -0.22225 -0.23876) (xy -0.22352 -0.24892) (xy -0.22606 -0.25908)
						(xy -0.22733 -0.27051) (xy -0.22733 -0.28067) (xy -0.2286 -0.2921) (xy -0.22733 -0.30353) (xy -0.22733 -0.31369)
						(xy -0.22606 -0.32512) (xy -0.22352 -0.33528) (xy -0.22225 -0.34544) (xy -0.21844 -0.35687) (xy -0.2159 -0.36703)
						(xy -0.21209 -0.37719) (xy -0.20701 -0.38735) (xy -0.2032 -0.39624) (xy -0.19812 -0.4064) (xy -0.17272 -0.44196)
						(xy -0.1651 -0.44958) (xy -0.1651 -0.7366) (xy -0.16256 -0.76835) (xy -0.1524 -0.8001) (xy -0.13716 -0.82804)
						(xy -0.11684 -0.85344) (xy -0.09144 -0.87376) (xy -0.0635 -0.889) (xy -0.03175 -0.89916) (xy 0 -0.9017)
						(xy 0.03175 -0.89916) (xy 0.0635 -0.889) (xy 0.09144 -0.87376) (xy 0.11684 -0.85344) (xy 0.13716 -0.82804)
						(xy 0.1524 -0.8001) (xy 0.16256 -0.76835) (xy 0.1651 -0.7366) (xy 0.1651 -0.44958) (xy 0.17272 -0.44196)
						(xy 0.19812 -0.4064) (xy 0.2032 -0.39624) (xy 0.20701 -0.38735) (xy 0.21209 -0.37719) (xy 0.2159 -0.36703)
						(xy 0.21844 -0.35687) (xy 0.22225 -0.34544) (xy 0.22352 -0.33528) (xy 0.22606 -0.32512) (xy 0.22733 -0.31369)
						(xy 0.22733 -0.30353) (xy 0.2286 -0.2921) (xy 0.22733 -0.28067) (xy 0.22733 -0.27051) (xy 0.22606 -0.25908)
						(xy 0.22352 -0.24892) (xy 0.22225 -0.23876) (xy 0.21844 -0.22733) (xy 0.2159 -0.21717) (xy 0.21209 -0.20701)
						(xy 0.20701 -0.19685) (xy 0.2032 -0.18796) (xy 0.19812 -0.1778) (xy 0.17272 -0.14224) (xy 0.1651 -0.13462)
						(xy 0.1651 0.7366) (xy 0.16256 0.76835) (xy 0.1524 0.8001) (xy 0.13716 0.82804) (xy 0.11684 0.85344)
						(xy 0.09144 0.87376) (xy 0.0635 0.889) (xy 0.03175 0.89916)
					)
					(width 0)
					(fill yes)
				)
			)
		)
		(pad "50" smd custom
			(at -16.949928 -4.106672)
			(size 0.1143 0.1143)
			(layers "F.Cu" "F.Mask" "F.Paste")
			(net "M_B_DQ19")
			(options
				(clearance outline)
				(anchor circle)
			)
			(primitives
				(gr_poly
					(pts
						(xy 0 0.9017) (xy -0.03175 0.89916) (xy -0.0635 0.889) (xy -0.09144 0.87376) (xy -0.11684 0.85344)
						(xy -0.13716 0.82804) (xy -0.1524 0.8001) (xy -0.16256 0.76835) (xy -0.1651 0.7366) (xy -0.1651 0.44958)
						(xy -0.17272 0.44196) (xy -0.19812 0.4064) (xy -0.2032 0.39624) (xy -0.20701 0.38735) (xy -0.21209 0.37719)
						(xy -0.2159 0.36703) (xy -0.21844 0.35687) (xy -0.22225 0.34544) (xy -0.22352 0.33528) (xy -0.22606 0.32512)
						(xy -0.22733 0.31369) (xy -0.22733 0.30353) (xy -0.2286 0.2921) (xy -0.22733 0.28067) (xy -0.22733 0.27051)
						(xy -0.22606 0.25908) (xy -0.22352 0.24892) (xy -0.22225 0.23876) (xy -0.21844 0.22733) (xy -0.2159 0.21717)
						(xy -0.21209 0.20701) (xy -0.20701 0.19685) (xy -0.2032 0.18796) (xy -0.19812 0.1778) (xy -0.17272 0.14224)
						(xy -0.1651 0.13462) (xy -0.1651 -0.7366) (xy -0.16256 -0.76835) (xy -0.1524 -0.8001) (xy -0.13716 -0.82804)
						(xy -0.11684 -0.85344) (xy -0.09144 -0.87376) (xy -0.0635 -0.889) (xy -0.03175 -0.89916) (xy 0 -0.9017)
						(xy 0.03175 -0.89916) (xy 0.0635 -0.889) (xy 0.09144 -0.87376) (xy 0.11684 -0.85344) (xy 0.13716 -0.82804)
						(xy 0.1524 -0.8001) (xy 0.16256 -0.76835) (xy 0.1651 -0.7366) (xy 0.1651 0.13462) (xy 0.17272 0.14224)
						(xy 0.19812 0.1778) (xy 0.2032 0.18796) (xy 0.20701 0.19685) (xy 0.21209 0.20701) (xy 0.2159 0.21717)
						(xy 0.21844 0.22733) (xy 0.22225 0.23876) (xy 0.22352 0.24892) (xy 0.22606 0.25908) (xy 0.22733 0.27051)
						(xy 0.22733 0.28067) (xy 0.2286 0.2921) (xy 0.22733 0.30353) (xy 0.22733 0.31369) (xy 0.22606 0.32512)
						(xy 0.22352 0.33528) (xy 0.22225 0.34544) (xy 0.21844 0.35687) (xy 0.2159 0.36703) (xy 0.21209 0.37719)
						(xy 0.20701 0.38735) (xy 0.2032 0.39624) (xy 0.19812 0.4064) (xy 0.17272 0.44196) (xy 0.1651 0.44958)
						(xy 0.1651 0.7366) (xy 0.16256 0.76835) (xy 0.1524 0.8001) (xy 0.13716 0.82804) (xy 0.11684 0.85344)
						(xy 0.09144 0.87376) (xy 0.0635 0.889) (xy 0.03175 0.89916)
					)
					(width 0)
					(fill yes)
				)
			)
		)
		(pad "51" smd custom
			(at -16.649954 4.106672)
			(size 0.1143 0.1143)
			(layers "F.Cu" "F.Mask" "F.Paste")
			(net "M_B_DQ23")
			(options
				(clearance outline)
				(anchor circle)
			)
			(primitives
				(gr_poly
					(pts
						(xy 0 0.9017) (xy -0.03175 0.89916) (xy -0.0635 0.889) (xy -0.09144 0.87376) (xy -0.11684 0.85344)
						(xy -0.13716 0.82804) (xy -0.1524 0.8001) (xy -0.16256 0.76835) (xy -0.1651 0.7366) (xy -0.1651 0.11938)
						(xy -0.17272 0.11176) (xy -0.19812 0.0762) (xy -0.2032 0.06604) (xy -0.20701 0.05715) (xy -0.21209 0.04699)
						(xy -0.2159 0.03683) (xy -0.21844 0.02667) (xy -0.22225 0.01524) (xy -0.22352 0.00508) (xy -0.22606 -0.00508)
						(xy -0.22733 -0.01651) (xy -0.22733 -0.02667) (xy -0.2286 -0.0381) (xy -0.22733 -0.04953) (xy -0.22733 -0.05969)
						(xy -0.22606 -0.07112) (xy -0.22352 -0.08128) (xy -0.22225 -0.09144) (xy -0.21844 -0.10287) (xy -0.2159 -0.11303)
						(xy -0.21209 -0.12319) (xy -0.20701 -0.13335) (xy -0.2032 -0.14224) (xy -0.19812 -0.1524) (xy -0.17272 -0.18796)
						(xy -0.1651 -0.19558) (xy -0.1651 -0.7366) (xy -0.16256 -0.76835) (xy -0.1524 -0.8001) (xy -0.13716 -0.82804)
						(xy -0.11684 -0.85344) (xy -0.09144 -0.87376) (xy -0.0635 -0.889) (xy -0.03175 -0.89916) (xy 0 -0.9017)
						(xy 0.03175 -0.89916) (xy 0.0635 -0.889) (xy 0.09144 -0.87376) (xy 0.11684 -0.85344) (xy 0.13716 -0.82804)
						(xy 0.1524 -0.8001) (xy 0.16256 -0.76835) (xy 0.1651 -0.7366) (xy 0.1651 -0.19685) (xy 0.17272 -0.18923)
						(xy 0.17907 -0.18034) (xy 0.18669 -0.17145) (xy 0.19177 -0.16256) (xy 0.19812 -0.15367) (xy 0.20828 -0.13335)
						(xy 0.21971 -0.10287) (xy 0.22225 -0.09271) (xy 0.22479 -0.08128) (xy 0.22606 -0.07112) (xy 0.2286 -0.05969)
						(xy 0.2286 -0.01651) (xy 0.22606 -0.00508) (xy 0.22479 0.00508) (xy 0.22225 0.01651) (xy 0.21971 0.02667)
						(xy 0.20828 0.05715) (xy 0.19812 0.07747) (xy 0.19177 0.08636) (xy 0.18669 0.09525) (xy 0.17907 0.10414)
						(xy 0.17272 0.11303) (xy 0.1651 0.12065) (xy 0.1651 0.7366) (xy 0.16256 0.76835) (xy 0.1524 0.8001)
						(xy 0.13716 0.82804) (xy 0.11684 0.85344) (xy 0.09144 0.87376) (xy 0.0635 0.889) (xy 0.03175 0.89916)
					)
					(width 0)
					(fill yes)
				)
			)
		)
		(pad "52" smd custom
			(at -16.34998 -4.106672)
			(size 0.1143 0.1143)
			(layers "F.Cu" "F.Mask" "F.Paste")
			(net "GND")
			(options
				(clearance outline)
				(anchor circle)
			)
			(primitives
				(gr_poly
					(pts
						(xy 0 0.9017) (xy -0.03175 0.89916) (xy -0.0635 0.889) (xy -0.09144 0.87376) (xy -0.11684 0.85344)
						(xy -0.13716 0.82804) (xy -0.1524 0.8001) (xy -0.16256 0.76835) (xy -0.1651 0.7366) (xy -0.1651 0.19685)
						(xy -0.17272 0.18923) (xy -0.17907 0.18034) (xy -0.18669 0.17145) (xy -0.19177 0.16256) (xy -0.19812 0.15367)
						(xy -0.20828 0.13335) (xy -0.21971 0.10287) (xy -0.22225 0.09271) (xy -0.22479 0.08128) (xy -0.22606 0.07112)
						(xy -0.2286 0.05969) (xy -0.2286 0.01651) (xy -0.22606 0.00508) (xy -0.22479 -0.00508) (xy -0.22225 -0.01651)
						(xy -0.21971 -0.02667) (xy -0.20828 -0.05715) (xy -0.19812 -0.07747) (xy -0.19177 -0.08636) (xy -0.18669 -0.09525)
						(xy -0.17907 -0.10414) (xy -0.17272 -0.11303) (xy -0.1651 -0.12065) (xy -0.1651 -0.7366) (xy -0.16256 -0.76835)
						(xy -0.1524 -0.8001) (xy -0.13716 -0.82804) (xy -0.11684 -0.85344) (xy -0.09144 -0.87376) (xy -0.0635 -0.889)
						(xy -0.03175 -0.89916) (xy 0 -0.9017) (xy 0.03175 -0.89916) (xy 0.0635 -0.889) (xy 0.09144 -0.87376)
						(xy 0.11684 -0.85344) (xy 0.13716 -0.82804) (xy 0.1524 -0.8001) (xy 0.16256 -0.76835) (xy 0.1651 -0.7366)
						(xy 0.1651 -0.11938) (xy 0.17272 -0.11176) (xy 0.19812 -0.0762) (xy 0.2032 -0.06604) (xy 0.20701 -0.05715)
						(xy 0.21209 -0.04699) (xy 0.2159 -0.03683) (xy 0.21844 -0.02667) (xy 0.22225 -0.01524) (xy 0.22352 -0.00508)
						(xy 0.22606 0.00508) (xy 0.22733 0.01651) (xy 0.22733 0.02667) (xy 0.2286 0.0381) (xy 0.22733 0.04953)
						(xy 0.22733 0.05969) (xy 0.22606 0.07112) (xy 0.22352 0.08128) (xy 0.22225 0.09144) (xy 0.21844 0.10287)
						(xy 0.2159 0.11303) (xy 0.21209 0.12319) (xy 0.20701 0.13335) (xy 0.2032 0.14224) (xy 0.19812 0.1524)
						(xy 0.17272 0.18796) (xy 0.1651 0.19558) (xy 0.1651 0.7366) (xy 0.16256 0.76835) (xy 0.1524 0.8001)
						(xy 0.13716 0.82804) (xy 0.11684 0.85344) (xy 0.09144 0.87376) (xy 0.0635 0.889) (xy 0.03175 0.89916)
					)
					(width 0)
					(fill yes)
				)
			)
		)
		(pad "53" smd custom
			(at -16.050006 4.106672)
			(size 0.1143 0.1143)
			(layers "F.Cu" "F.Mask" "F.Paste")
			(net "GND")
			(options
				(clearance outline)
				(anchor circle)
			)
			(primitives
				(gr_poly
					(pts
						(xy 0 0.9017) (xy -0.03175 0.89916) (xy -0.0635 0.889) (xy -0.09144 0.87376) (xy -0.11684 0.85344)
						(xy -0.13716 0.82804) (xy -0.1524 0.8001) (xy -0.16256 0.76835) (xy -0.1651 0.7366) (xy -0.1651 -0.13462)
						(xy -0.17272 -0.14224) (xy -0.19812 -0.1778) (xy -0.2032 -0.18796) (xy -0.20701 -0.19685) (xy -0.21209 -0.20701)
						(xy -0.2159 -0.21717) (xy -0.21844 -0.22733) (xy -0.22225 -0.23876) (xy -0.22352 -0.24892) (xy -0.22606 -0.25908)
						(xy -0.22733 -0.27051) (xy -0.22733 -0.28067) (xy -0.2286 -0.2921) (xy -0.22733 -0.30353) (xy -0.22733 -0.31369)
						(xy -0.22606 -0.32512) (xy -0.22352 -0.33528) (xy -0.22225 -0.34544) (xy -0.21844 -0.35687) (xy -0.2159 -0.36703)
						(xy -0.21209 -0.37719) (xy -0.20701 -0.38735) (xy -0.2032 -0.39624) (xy -0.19812 -0.4064) (xy -0.17272 -0.44196)
						(xy -0.1651 -0.44958) (xy -0.1651 -0.7366) (xy -0.16256 -0.76835) (xy -0.1524 -0.8001) (xy -0.13716 -0.82804)
						(xy -0.11684 -0.85344) (xy -0.09144 -0.87376) (xy -0.0635 -0.889) (xy -0.03175 -0.89916) (xy 0 -0.9017)
						(xy 0.03175 -0.89916) (xy 0.0635 -0.889) (xy 0.09144 -0.87376) (xy 0.11684 -0.85344) (xy 0.13716 -0.82804)
						(xy 0.1524 -0.8001) (xy 0.16256 -0.76835) (xy 0.1651 -0.7366) (xy 0.1651 -0.44958) (xy 0.17272 -0.44196)
						(xy 0.19812 -0.4064) (xy 0.2032 -0.39624) (xy 0.20701 -0.38735) (xy 0.21209 -0.37719) (xy 0.2159 -0.36703)
						(xy 0.21844 -0.35687) (xy 0.22225 -0.34544) (xy 0.22352 -0.33528) (xy 0.22606 -0.32512) (xy 0.22733 -0.31369)
						(xy 0.22733 -0.30353) (xy 0.2286 -0.2921) (xy 0.22733 -0.28067) (xy 0.22733 -0.27051) (xy 0.22606 -0.25908)
						(xy 0.22352 -0.24892) (xy 0.22225 -0.23876) (xy 0.21844 -0.22733) (xy 0.2159 -0.21717) (xy 0.21209 -0.20701)
						(xy 0.20701 -0.19685) (xy 0.2032 -0.18796) (xy 0.19812 -0.1778) (xy 0.17272 -0.14224) (xy 0.1651 -0.13462)
						(xy 0.1651 0.7366) (xy 0.16256 0.76835) (xy 0.1524 0.8001) (xy 0.13716 0.82804) (xy 0.11684 0.85344)
						(xy 0.09144 0.87376) (xy 0.0635 0.889) (xy 0.03175 0.89916)
					)
					(width 0)
					(fill yes)
				)
			)
		)
		(pad "54" smd custom
			(at -15.750032 -4.106672)
			(size 0.1143 0.1143)
			(layers "F.Cu" "F.Mask" "F.Paste")
			(net "M_B_DQ24")
			(options
				(clearance outline)
				(anchor circle)
			)
			(primitives
				(gr_poly
					(pts
						(xy 0 0.9017) (xy -0.03175 0.89916) (xy -0.0635 0.889) (xy -0.09144 0.87376) (xy -0.11684 0.85344)
						(xy -0.13716 0.82804) (xy -0.1524 0.8001) (xy -0.16256 0.76835) (xy -0.1651 0.7366) (xy -0.1651 0.44958)
						(xy -0.17272 0.44196) (xy -0.19812 0.4064) (xy -0.2032 0.39624) (xy -0.20701 0.38735) (xy -0.21209 0.37719)
						(xy -0.2159 0.36703) (xy -0.21844 0.35687) (xy -0.22225 0.34544) (xy -0.22352 0.33528) (xy -0.22606 0.32512)
						(xy -0.22733 0.31369) (xy -0.22733 0.30353) (xy -0.2286 0.2921) (xy -0.22733 0.28067) (xy -0.22733 0.27051)
						(xy -0.22606 0.25908) (xy -0.22352 0.24892) (xy -0.22225 0.23876) (xy -0.21844 0.22733) (xy -0.2159 0.21717)
						(xy -0.21209 0.20701) (xy -0.20701 0.19685) (xy -0.2032 0.18796) (xy -0.19812 0.1778) (xy -0.17272 0.14224)
						(xy -0.1651 0.13462) (xy -0.1651 -0.7366) (xy -0.16256 -0.76835) (xy -0.1524 -0.8001) (xy -0.13716 -0.82804)
						(xy -0.11684 -0.85344) (xy -0.09144 -0.87376) (xy -0.0635 -0.889) (xy -0.03175 -0.89916) (xy 0 -0.9017)
						(xy 0.03175 -0.89916) (xy 0.0635 -0.889) (xy 0.09144 -0.87376) (xy 0.11684 -0.85344) (xy 0.13716 -0.82804)
						(xy 0.1524 -0.8001) (xy 0.16256 -0.76835) (xy 0.1651 -0.7366) (xy 0.1651 0.13462) (xy 0.17272 0.14224)
						(xy 0.19812 0.1778) (xy 0.2032 0.18796) (xy 0.20701 0.19685) (xy 0.21209 0.20701) (xy 0.2159 0.21717)
						(xy 0.21844 0.22733) (xy 0.22225 0.23876) (xy 0.22352 0.24892) (xy 0.22606 0.25908) (xy 0.22733 0.27051)
						(xy 0.22733 0.28067) (xy 0.2286 0.2921) (xy 0.22733 0.30353) (xy 0.22733 0.31369) (xy 0.22606 0.32512)
						(xy 0.22352 0.33528) (xy 0.22225 0.34544) (xy 0.21844 0.35687) (xy 0.2159 0.36703) (xy 0.21209 0.37719)
						(xy 0.20701 0.38735) (xy 0.2032 0.39624) (xy 0.19812 0.4064) (xy 0.17272 0.44196) (xy 0.1651 0.44958)
						(xy 0.1651 0.7366) (xy 0.16256 0.76835) (xy 0.1524 0.8001) (xy 0.13716 0.82804) (xy 0.11684 0.85344)
						(xy 0.09144 0.87376) (xy 0.0635 0.889) (xy 0.03175 0.89916)
					)
					(width 0)
					(fill yes)
				)
			)
		)
		(pad "55" smd custom
			(at -15.450058 4.106672)
			(size 0.1143 0.1143)
			(layers "F.Cu" "F.Mask" "F.Paste")
			(net "M_B_DQ28")
			(options
				(clearance outline)
				(anchor circle)
			)
			(primitives
				(gr_poly
					(pts
						(xy 0 0.9017) (xy -0.03175 0.89916) (xy -0.0635 0.889) (xy -0.09144 0.87376) (xy -0.11684 0.85344)
						(xy -0.13716 0.82804) (xy -0.1524 0.8001) (xy -0.16256 0.76835) (xy -0.1651 0.7366) (xy -0.1651 0.11938)
						(xy -0.17272 0.11176) (xy -0.19812 0.0762) (xy -0.2032 0.06604) (xy -0.20701 0.05715) (xy -0.21209 0.04699)
						(xy -0.2159 0.03683) (xy -0.21844 0.02667) (xy -0.22225 0.01524) (xy -0.22352 0.00508) (xy -0.22606 -0.00508)
						(xy -0.22733 -0.01651) (xy -0.22733 -0.02667) (xy -0.2286 -0.0381) (xy -0.22733 -0.04953) (xy -0.22733 -0.05969)
						(xy -0.22606 -0.07112) (xy -0.22352 -0.08128) (xy -0.22225 -0.09144) (xy -0.21844 -0.10287) (xy -0.2159 -0.11303)
						(xy -0.21209 -0.12319) (xy -0.20701 -0.13335) (xy -0.2032 -0.14224) (xy -0.19812 -0.1524) (xy -0.17272 -0.18796)
						(xy -0.1651 -0.19558) (xy -0.1651 -0.7366) (xy -0.16256 -0.76835) (xy -0.1524 -0.8001) (xy -0.13716 -0.82804)
						(xy -0.11684 -0.85344) (xy -0.09144 -0.87376) (xy -0.0635 -0.889) (xy -0.03175 -0.89916) (xy 0 -0.9017)
						(xy 0.03175 -0.89916) (xy 0.0635 -0.889) (xy 0.09144 -0.87376) (xy 0.11684 -0.85344) (xy 0.13716 -0.82804)
						(xy 0.1524 -0.8001) (xy 0.16256 -0.76835) (xy 0.1651 -0.7366) (xy 0.1651 -0.19685) (xy 0.17272 -0.18923)
						(xy 0.17907 -0.18034) (xy 0.18669 -0.17145) (xy 0.19177 -0.16256) (xy 0.19812 -0.15367) (xy 0.20828 -0.13335)
						(xy 0.21971 -0.10287) (xy 0.22225 -0.09271) (xy 0.22479 -0.08128) (xy 0.22606 -0.07112) (xy 0.2286 -0.05969)
						(xy 0.2286 -0.01651) (xy 0.22606 -0.00508) (xy 0.22479 0.00508) (xy 0.22225 0.01651) (xy 0.21971 0.02667)
						(xy 0.20828 0.05715) (xy 0.19812 0.07747) (xy 0.19177 0.08636) (xy 0.18669 0.09525) (xy 0.17907 0.10414)
						(xy 0.17272 0.11303) (xy 0.1651 0.12065) (xy 0.1651 0.7366) (xy 0.16256 0.76835) (xy 0.1524 0.8001)
						(xy 0.13716 0.82804) (xy 0.11684 0.85344) (xy 0.09144 0.87376) (xy 0.0635 0.889) (xy 0.03175 0.89916)
					)
					(width 0)
					(fill yes)
				)
			)
		)
	)
)
